(kicad_pcb
	(version 20260206)
	(generator "pcbnew")
	(generator_version "10.0")
	(general
		(thickness 1.6)
		(legacy_teardrops no)
	)
	(paper "A4")
	(title_block
		(title "01162023_DA0F0TEBIF0_F0T_Expander_BD_F_brd_V02_OCP.brd")
		(comment 1 "Grand Teton / footprints 5474-5481 of 9728")
	)
	(layers
		(0 "F.Cu" signal "TOP")
		(4 "In1.Cu" signal "GND")
		(6 "In2.Cu" signal "VCC")
		(8 "In3.Cu" signal "VCC1")
		(10 "In4.Cu" signal "GND1")
		(12 "In5.Cu" signal "IN1")
		(14 "In6.Cu" signal "GND2")
		(16 "In7.Cu" signal "IN2")
		(18 "In8.Cu" signal "GND3")
		(20 "In9.Cu" signal "IN3")
		(22 "In10.Cu" signal "GND4")
		(24 "In11.Cu" signal "IN4")
		(26 "In12.Cu" signal "GND5")
		(28 "In13.Cu" signal "IN5")
		(30 "In14.Cu" signal "GND6")
		(32 "In15.Cu" signal "IN6")
		(34 "In16.Cu" signal "GND7")
		(2 "B.Cu" signal "BOTTOM")
		(9 "F.Adhes" user "F.Adhesive")
		(11 "B.Adhes" user "B.Adhesive")
		(13 "F.Paste" user "Package Geometry/Pastemask Top")
		(15 "B.Paste" user "Package Geometry/Pastemask Bottom")
		(5 "F.SilkS" user "Ref Des/Silkscreen Top")
		(7 "B.SilkS" user "Ref Des/Silkscreen Bottom")
		(1 "F.Mask" user "Board Geometry/Soldermask Top")
		(3 "B.Mask" user "Board Geometry/Soldermask Bottom")
		(17 "Dwgs.User" user "User.Drawings")
		(19 "Cmts.User" user "User.Comments")
		(21 "Eco1.User" user "User.Eco1")
		(23 "Eco2.User" user "User.Eco2")
		(25 "Edge.Cuts" user "Board Geometry/Outline")
		(27 "Margin" user)
		(31 "F.CrtYd" user "Package Geometry/Place Bound Top")
		(29 "B.CrtYd" user "Package Geometry/Place Bound Bottom")
		(35 "F.Fab" user "Ref Des/Assembly Top")
		(33 "B.Fab" user "Ref Des/Assembly Bottom")
	)
	(footprint ""
		(layer "F.Cu")
		(at 378.382022 -299.391832 180)
		(property "Reference" "C3553"
			(at 0 0 180)
			(layer "F.SilkS")
			(hide yes)
			(effects
				(font
					(size 1.27 1.27)
				)
			)
		)
		(property "Value" ""
			(at 0 0 180)
			(layer "F.Fab")
			(effects
				(font
					(size 1.27 1.27)
				)
			)
		)
		(duplicate_pad_numbers_are_jumpers no)
		(fp_line
			(start 1.2954 0.5842)
			(end -1.2954 0.5842)
			(stroke
				(width 0.1524)
				(type default)
			)
			(layer "F.SilkS")
		)
		(fp_line
			(start 1.2954 -0.5842)
			(end 1.2954 0.5842)
			(stroke
				(width 0.1524)
				(type default)
			)
			(layer "F.SilkS")
		)
		(fp_line
			(start -1.2954 0.5842)
			(end -1.2954 -0.5842)
			(stroke
				(width 0.1524)
				(type default)
			)
			(layer "F.SilkS")
		)
		(fp_line
			(start -1.2954 -0.5842)
			(end 1.2954 -0.5842)
			(stroke
				(width 0.1524)
				(type default)
			)
			(layer "F.SilkS")
		)
		(fp_line
			(start 1.1938 0.4064)
			(end 0.8636 0.4064)
			(stroke
				(width 0.1)
				(type default)
			)
			(layer "F.Fab")
		)
		(fp_line
			(start 1.1938 -0.4064)
			(end 1.1938 0.4064)
			(stroke
				(width 0.1)
				(type default)
			)
			(layer "F.Fab")
		)
		(fp_line
			(start 0.8636 0.4572)
			(end -0.8636 0.4572)
			(stroke
				(width 0.1)
				(type default)
			)
			(layer "F.Fab")
		)
		(fp_line
			(start 0.8636 0.4064)
			(end 0.8636 0.4572)
			(stroke
				(width 0.1)
				(type default)
			)
			(layer "F.Fab")
		)
		(fp_line
			(start 0.8636 -0.4064)
			(end 1.1938 -0.4064)
			(stroke
				(width 0.1)
				(type default)
			)
			(layer "F.Fab")
		)
		(fp_line
			(start 0.8636 -0.4572)
			(end 0.8636 -0.4064)
			(stroke
				(width 0.1)
				(type default)
			)
			(layer "F.Fab")
		)
		(fp_line
			(start -0.8636 0.4572)
			(end -0.8636 0.4064)
			(stroke
				(width 0.1)
				(type default)
			)
			(layer "F.Fab")
		)
		(fp_line
			(start -0.8636 0.4064)
			(end -1.1938 0.4064)
			(stroke
				(width 0.1)
				(type default)
			)
			(layer "F.Fab")
		)
		(fp_line
			(start -0.8636 -0.4064)
			(end -0.8636 -0.4572)
			(stroke
				(width 0.1)
				(type default)
			)
			(layer "F.Fab")
		)
		(fp_line
			(start -0.8636 -0.4572)
			(end 0.8636 -0.4572)
			(stroke
				(width 0.1)
				(type default)
			)
			(layer "F.Fab")
		)
		(fp_line
			(start -1.1938 0.4064)
			(end -1.1938 -0.4064)
			(stroke
				(width 0.1)
				(type default)
			)
			(layer "F.Fab")
		)
		(fp_line
			(start -1.1938 -0.4064)
			(end -0.8636 -0.4064)
			(stroke
				(width 0.1)
				(type default)
			)
			(layer "F.Fab")
		)
		(pad "1" smd rect
			(at -0.7366 0 90)
			(size 0.7112 0.8128)
			(layers "F.Cu" "F.Mask" "F.Paste")
			(net "PCEPLL1_VDDA18_PEX3_R")
		)
		(pad "2" smd rect
			(at 0.7366 0 90)
			(size 0.7112 0.8128)
			(layers "F.Cu" "F.Mask" "F.Paste")
			(net "GND")
		)
	)
	(footprint ""
		(layer "F.Cu")
		(at 105.287826 -319.420494 90)
		(property "Reference" "R5783"
			(at 0 0 90)
			(layer "F.SilkS")
			(hide yes)
			(effects
				(font
					(size 1.27 1.27)
				)
			)
		)
		(property "Value" ""
			(at 0 0 90)
			(layer "F.Fab")
			(effects
				(font
					(size 1.27 1.27)
				)
			)
		)
		(duplicate_pad_numbers_are_jumpers no)
		(fp_line
			(start 2.576322 -1.1303)
			(end 2.576322 1.1303)
			(stroke
				(width 0.1524)
				(type default)
			)
			(layer "F.SilkS")
		)
		(fp_line
			(start -2.576322 -1.1303)
			(end 2.576322 -1.1303)
			(stroke
				(width 0.1524)
				(type default)
			)
			(layer "F.SilkS")
		)
		(fp_line
			(start 2.576322 1.1303)
			(end -2.576322 1.1303)
			(stroke
				(width 0.1524)
				(type default)
			)
			(layer "F.SilkS")
		)
		(fp_line
			(start -2.576322 1.1303)
			(end -2.576322 -1.1303)
			(stroke
				(width 0.1524)
				(type default)
			)
			(layer "F.SilkS")
		)
		(fp_line
			(start 1.649984 -0.899922)
			(end -1.649984 -0.899922)
			(stroke
				(width 0.1)
				(type default)
			)
			(layer "F.Fab")
		)
		(fp_line
			(start -1.649984 -0.899922)
			(end -1.649984 0.899922)
			(stroke
				(width 0.1)
				(type default)
			)
			(layer "F.Fab")
		)
		(fp_line
			(start 1.649984 0.899922)
			(end 1.649984 -0.899922)
			(stroke
				(width 0.1)
				(type default)
			)
			(layer "F.Fab")
		)
		(fp_line
			(start -1.649984 0.899922)
			(end 1.649984 0.899922)
			(stroke
				(width 0.1)
				(type default)
			)
			(layer "F.Fab")
		)
		(pad "1A" smd rect
			(at -1.700022 0 90)
			(size 1.4986 2.0066)
			(layers "F.Cu" "F.Mask" "F.Paste")
			(net "P0V8_PEX0")
		)
		(pad "1B" smd rect
			(at -1.077722 0 90)
			(size 0.254 0.508)
			(layers "F.Cu" "F.Mask" "F.Paste")
			(net "P0V8_PEX0")
		)
		(pad "2A" smd rect
			(at 1.700022 0 90)
			(size 1.4986 2.0066)
			(layers "F.Cu" "F.Mask" "F.Paste")
			(net "P0V8_SERDES_VDDA_PEX0")
		)
		(pad "2B" smd rect
			(at 1.077722 0 90)
			(size 0.254 0.508)
			(layers "F.Cu" "F.Mask" "F.Paste")
			(net "P0V8_SERDES_VDDA_PEX0")
		)
	)
	(footprint ""
		(layer "F.Cu")
		(at 106.385106 -380.898908 -90)
		(property "Reference" "R5447"
			(at 0 0 270)
			(layer "F.SilkS")
			(hide yes)
			(effects
				(font
					(size 1.27 1.27)
				)
			)
		)
		(property "Value" ""
			(at 0 0 270)
			(layer "F.Fab")
			(effects
				(font
					(size 1.27 1.27)
				)
			)
		)
		(duplicate_pad_numbers_are_jumpers no)
		(fp_line
			(start 0.02794 0.4064)
			(end -0.7874 0.4064)
			(stroke
				(width 0.1524)
				(type default)
			)
			(layer "F.SilkS")
		)
		(fp_line
			(start -0.7874 -0.4064)
			(end 0.7874 -0.4064)
			(stroke
				(width 0.1524)
				(type default)
			)
			(layer "F.SilkS")
		)
		(fp_line
			(start 0.7874 -0.4064)
			(end 0.7874 0.4064)
			(stroke
				(width 0.1524)
				(type default)
			)
			(layer "F.SilkS")
		)
		(fp_line
			(start -0.67945 0.3048)
			(end -0.67945 -0.305054)
			(stroke
				(width 0.1)
				(type default)
			)
			(layer "F.Fab")
		)
		(fp_line
			(start -0.12065 0.3048)
			(end -0.67945 0.3048)
			(stroke
				(width 0.1)
				(type default)
			)
			(layer "F.Fab")
		)
		(fp_line
			(start 0.120396 0.3048)
			(end 0.120396 0.2794)
			(stroke
				(width 0.1)
				(type default)
			)
			(layer "F.Fab")
		)
		(fp_line
			(start 0.67945 0.3048)
			(end 0.120396 0.3048)
			(stroke
				(width 0.1)
				(type default)
			)
			(layer "F.Fab")
		)
		(fp_line
			(start -0.12065 0.2794)
			(end -0.12065 0.3048)
			(stroke
				(width 0.1)
				(type default)
			)
			(layer "F.Fab")
		)
		(fp_line
			(start 0.120396 0.2794)
			(end -0.12065 0.2794)
			(stroke
				(width 0.1)
				(type default)
			)
			(layer "F.Fab")
		)
		(fp_line
			(start -0.12065 -0.2794)
			(end 0.12065 -0.2794)
			(stroke
				(width 0.1)
				(type default)
			)
			(layer "F.Fab")
		)
		(fp_line
			(start 0.12065 -0.2794)
			(end 0.12065 -0.3048)
			(stroke
				(width 0.1)
				(type default)
			)
			(layer "F.Fab")
		)
		(fp_line
			(start 0.12065 -0.3048)
			(end 0.67945 -0.3048)
			(stroke
				(width 0.1)
				(type default)
			)
			(layer "F.Fab")
		)
		(fp_line
			(start 0.67945 -0.3048)
			(end 0.67945 0.3048)
			(stroke
				(width 0.1)
				(type default)
			)
			(layer "F.Fab")
		)
		(fp_line
			(start -0.67945 -0.305054)
			(end -0.12065 -0.305054)
			(stroke
				(width 0.1)
				(type default)
			)
			(layer "F.Fab")
		)
		(fp_line
			(start -0.12065 -0.305054)
			(end -0.12065 -0.2794)
			(stroke
				(width 0.1)
				(type default)
			)
			(layer "F.Fab")
		)
		(pad "1" smd rect
			(at -0.40005 0 90)
			(size 0.4572 0.508)
			(layers "F.Cu" "F.Mask" "F.Paste")
			(net "USB2_BIC_R_DP")
		)
		(pad "2" smd rect
			(at 0.40005 0 90)
			(size 0.4572 0.508)
			(layers "F.Cu" "F.Mask" "F.Paste")
			(net "USB2_BIC_DP")
		)
	)
	(footprint ""
		(layer "F.Cu")
		(at 215.075516 -120.239028)
		(property "Reference" "PR253"
			(at 0 0 0)
			(layer "F.SilkS")
			(hide yes)
			(effects
				(font
					(size 1.27 1.27)
				)
			)
		)
		(property "Value" ""
			(at 0 0 0)
			(layer "F.Fab")
			(effects
				(font
					(size 1.27 1.27)
				)
			)
		)
		(duplicate_pad_numbers_are_jumpers no)
		(fp_line
			(start -0.7874 -0.4064)
			(end 0.7874 -0.4064)
			(stroke
				(width 0.1524)
				(type default)
			)
			(layer "F.SilkS")
		)
		(fp_line
			(start -0.7874 0.4064)
			(end -0.7874 -0.4064)
			(stroke
				(width 0.1524)
				(type default)
			)
			(layer "F.SilkS")
		)
		(fp_line
			(start 0.7874 -0.4064)
			(end 0.7874 0.4064)
			(stroke
				(width 0.1524)
				(type default)
			)
			(layer "F.SilkS")
		)
		(fp_line
			(start 0.7874 0.4064)
			(end -0.7874 0.4064)
			(stroke
				(width 0.1524)
				(type default)
			)
			(layer "F.SilkS")
		)
		(fp_line
			(start -0.67945 -0.305054)
			(end -0.12065 -0.305054)
			(stroke
				(width 0.1)
				(type default)
			)
			(layer "F.Fab")
		)
		(fp_line
			(start -0.67945 0.3048)
			(end -0.67945 -0.305054)
			(stroke
				(width 0.1)
				(type default)
			)
			(layer "F.Fab")
		)
		(fp_line
			(start -0.12065 -0.305054)
			(end -0.12065 -0.2794)
			(stroke
				(width 0.1)
				(type default)
			)
			(layer "F.Fab")
		)
		(fp_line
			(start -0.12065 -0.2794)
			(end 0.12065 -0.2794)
			(stroke
				(width 0.1)
				(type default)
			)
			(layer "F.Fab")
		)
		(fp_line
			(start -0.12065 0.2794)
			(end -0.12065 0.3048)
			(stroke
				(width 0.1)
				(type default)
			)
			(layer "F.Fab")
		)
		(fp_line
			(start -0.12065 0.3048)
			(end -0.67945 0.3048)
			(stroke
				(width 0.1)
				(type default)
			)
			(layer "F.Fab")
		)
		(fp_line
			(start 0.120396 0.2794)
			(end -0.12065 0.2794)
			(stroke
				(width 0.1)
				(type default)
			)
			(layer "F.Fab")
		)
		(fp_line
			(start 0.120396 0.3048)
			(end 0.120396 0.2794)
			(stroke
				(width 0.1)
				(type default)
			)
			(layer "F.Fab")
		)
		(fp_line
			(start 0.12065 -0.3048)
			(end 0.67945 -0.3048)
			(stroke
				(width 0.1)
				(type default)
			)
			(layer "F.Fab")
		)
		(fp_line
			(start 0.12065 -0.2794)
			(end 0.12065 -0.3048)
			(stroke
				(width 0.1)
				(type default)
			)
			(layer "F.Fab")
		)
		(fp_line
			(start 0.67945 -0.3048)
			(end 0.67945 0.3048)
			(stroke
				(width 0.1)
				(type default)
			)
			(layer "F.Fab")
		)
		(fp_line
			(start 0.67945 0.3048)
			(end 0.120396 0.3048)
			(stroke
				(width 0.1)
				(type default)
			)
			(layer "F.Fab")
		)
		(pad "1" smd circle
			(at -0.40005 0)
			(size 0 0)
			(layers "F.Cu" "F.Mask" "F.Paste")
			(net "P3V3_NIC3_OCP")
		)
		(pad "2" smd circle
			(at 0.40005 0)
			(size 0 0)
			(layers "F.Cu" "F.Mask" "F.Paste")
			(net "GND")
		)
	)
	(footprint ""
		(layer "F.Cu")
		(at 440.359292 -356.244906 90)
		(property "Reference" "C794"
			(at 0 0 90)
			(layer "F.SilkS")
			(hide yes)
			(effects
				(font
					(size 1.27 1.27)
				)
			)
		)
		(property "Value" ""
			(at 0 0 90)
			(layer "F.Fab")
			(effects
				(font
					(size 1.27 1.27)
				)
			)
		)
		(duplicate_pad_numbers_are_jumpers no)
		(fp_line
			(start 0.299974 -0.150114)
			(end 0.299974 0.150114)
			(stroke
				(width 0.1)
				(type default)
			)
			(layer "F.Fab")
		)
		(fp_line
			(start -0.299974 -0.150114)
			(end 0.299974 -0.150114)
			(stroke
				(width 0.1)
				(type default)
			)
			(layer "F.Fab")
		)
		(fp_line
			(start 0.299974 0.150114)
			(end -0.299974 0.150114)
			(stroke
				(width 0.1)
				(type default)
			)
			(layer "F.Fab")
		)
		(fp_line
			(start -0.299974 0.150114)
			(end -0.299974 -0.150114)
			(stroke
				(width 0.1)
				(type default)
			)
			(layer "F.Fab")
		)
		(pad "1" smd rect
			(at -0.2667 0 90)
			(size 0.3048 0.381)
			(layers "F.Cu" "F.Mask" "F.Paste")
			(net "P5E_PEX3_STN7_TX_DP<127>")
		)
		(pad "2" smd rect
			(at 0.2667 0 90)
			(size 0.3048 0.381)
			(layers "F.Cu" "F.Mask" "F.Paste")
			(net "P5E_PEX3_STN7_TX_C_DP<127>")
		)
	)
	(footprint ""
		(layer "F.Cu")
		(at 491.839758 -549.60774 180)
		(property "Reference" "SCREW_2"
			(at -3.2385 -1.402334 0)
			(unlocked yes)
			(layer "B.SilkS")
			(effects
				(font
					(size 0.7874 0.5842)
					(thickness 0.1524)
				)
				(justify mirror)
			)
		)
		(property "Value" ""
			(at 0 0 180)
			(layer "F.Fab")
			(effects
				(font
					(size 1.27 1.27)
				)
			)
		)
		(duplicate_pad_numbers_are_jumpers no)
		(pad "1" thru_hole circle
			(at 0 0 180)
			(size 0.4572 0.4572)
			(drill 0.2032)
			(layers "*.Cu" "*.Mask")
			(remove_unused_layers no)
			(net "Net_9162")
			(clearance 0.127)
			(thermal_gap 0.127)
			(padstack
				(mode front_inner_back)
				(layer "Inner"
					(shape circle)
					(size 0.4572 0.4572)
					(clearance 0.127)
				)
				(layer "B.Cu"
					(shape circle)
					(size 0.508 0.508)
					(clearance 0.1016)
				)
			)
		)
	)
	(footprint ""
		(layer "F.Cu")
		(at 326.012556 -195.218304 180)
		(property "Reference" "R4234"
			(at 0 0 180)
			(layer "F.SilkS")
			(hide yes)
			(effects
				(font
					(size 1.27 1.27)
				)
			)
		)
		(property "Value" ""
			(at 0 0 180)
			(layer "F.Fab")
			(effects
				(font
					(size 1.27 1.27)
				)
			)
		)
		(duplicate_pad_numbers_are_jumpers no)
		(fp_line
			(start 0.7874 0.4064)
			(end -0.7874 0.4064)
			(stroke
				(width 0.1524)
				(type default)
			)
			(layer "F.SilkS")
		)
		(fp_line
			(start 0.7874 -0.4064)
			(end 0.7874 0.4064)
			(stroke
				(width 0.1524)
				(type default)
			)
			(layer "F.SilkS")
		)
		(fp_line
			(start -0.7874 0.4064)
			(end -0.7874 -0.4064)
			(stroke
				(width 0.1524)
				(type default)
			)
			(layer "F.SilkS")
		)
		(fp_line
			(start -0.7874 -0.4064)
			(end 0.7874 -0.4064)
			(stroke
				(width 0.1524)
				(type default)
			)
			(layer "F.SilkS")
		)
		(fp_line
			(start 0.67945 0.3048)
			(end 0.120396 0.3048)
			(stroke
				(width 0.1)
				(type default)
			)
			(layer "F.Fab")
		)
		(fp_line
			(start 0.67945 -0.3048)
			(end 0.67945 0.3048)
			(stroke
				(width 0.1)
				(type default)
			)
			(layer "F.Fab")
		)
		(fp_line
			(start 0.12065 -0.2794)
			(end 0.12065 -0.3048)
			(stroke
				(width 0.1)
				(type default)
			)
			(layer "F.Fab")
		)
		(fp_line
			(start 0.12065 -0.3048)
			(end 0.67945 -0.3048)
			(stroke
				(width 0.1)
				(type default)
			)
			(layer "F.Fab")
		)
		(fp_line
			(start 0.120396 0.3048)
			(end 0.120396 0.2794)
			(stroke
				(width 0.1)
				(type default)
			)
			(layer "F.Fab")
		)
		(fp_line
			(start 0.120396 0.2794)
			(end -0.12065 0.2794)
			(stroke
				(width 0.1)
				(type default)
			)
			(layer "F.Fab")
		)
		(fp_line
			(start -0.12065 0.3048)
			(end -0.67945 0.3048)
			(stroke
				(width 0.1)
				(type default)
			)
			(layer "F.Fab")
		)
		(fp_line
			(start -0.12065 0.2794)
			(end -0.12065 0.3048)
			(stroke
				(width 0.1)
				(type default)
			)
			(layer "F.Fab")
		)
		(fp_line
			(start -0.12065 -0.2794)
			(end 0.12065 -0.2794)
			(stroke
				(width 0.1)
				(type default)
			)
			(layer "F.Fab")
		)
		(fp_line
			(start -0.12065 -0.305054)
			(end -0.12065 -0.2794)
			(stroke
				(width 0.1)
				(type default)
			)
			(layer "F.Fab")
		)
		(fp_line
			(start -0.67945 0.3048)
			(end -0.67945 -0.305054)
			(stroke
				(width 0.1)
				(type default)
			)
			(layer "F.Fab")
		)
		(fp_line
			(start -0.67945 -0.305054)
			(end -0.12065 -0.305054)
			(stroke
				(width 0.1)
				(type default)
			)
			(layer "F.Fab")
		)
		(pad "1" smd circle
			(at -0.40005 0 180)
			(size 0 0)
			(layers "F.Cu" "F.Mask" "F.Paste")
			(net "IOEXP_DBV2_A2")
		)
		(pad "2" smd circle
			(at 0.40005 0 180)
			(size 0 0)
			(layers "F.Cu" "F.Mask" "F.Paste")
			(net "P3V3_AUX")
		)
	)
	(footprint ""
		(layer "F.Cu")
		(at 175.510952 -343.952322 90)
		(property "Reference" "C391"
			(at 0 0 90)
			(layer "F.SilkS")
			(hide yes)
			(effects
				(font
					(size 1.27 1.27)
				)
			)
		)
		(property "Value" ""
			(at 0 0 90)
			(layer "F.Fab")
			(effects
				(font
					(size 1.27 1.27)
				)
			)
		)
		(duplicate_pad_numbers_are_jumpers no)
		(fp_line
			(start 0.299974 -0.150114)
			(end 0.299974 0.150114)
			(stroke
				(width 0.1)
				(type default)
			)
			(layer "F.Fab")
		)
		(fp_line
			(start -0.299974 -0.150114)
			(end 0.299974 -0.150114)
			(stroke
				(width 0.1)
				(type default)
			)
			(layer "F.Fab")
		)
		(fp_line
			(start 0.299974 0.150114)
			(end -0.299974 0.150114)
			(stroke
				(width 0.1)
				(type default)
			)
			(layer "F.Fab")
		)
		(fp_line
			(start -0.299974 0.150114)
			(end -0.299974 -0.150114)
			(stroke
				(width 0.1)
				(type default)
			)
			(layer "F.Fab")
		)
		(pad "1" smd rect
			(at -0.2667 0 90)
			(size 0.3048 0.381)
			(layers "F.Cu" "F.Mask" "F.Paste")
			(net "P5E_PEX1_STN7_TX_DN<118>")
		)
		(pad "2" smd rect
			(at 0.2667 0 90)
			(size 0.3048 0.381)
			(layers "F.Cu" "F.Mask" "F.Paste")
			(net "P5E_PEX1_STN7_TX_C_DN<118>")
		)
	)
)
